(kicad_pcb
	(version 20260206)
	(generator "pcbnew")
	(generator_version "10.0")
	(general
		(thickness 1.6)
		(legacy_teardrops no)
	)
	(paper "A4")
	(title_block
		(title "01162023_DA0F0TEBIF0_F0T_Expander_BD_F_brd_V02_OCP.brd")
		(comment 1 "Grand Teton / footprints 9555-9561 of 9728")
	)
	(layers
		(0 "F.Cu" signal "TOP")
		(4 "In1.Cu" signal "GND")
		(6 "In2.Cu" signal "VCC")
		(8 "In3.Cu" signal "VCC1")
		(10 "In4.Cu" signal "GND1")
		(12 "In5.Cu" signal "IN1")
		(14 "In6.Cu" signal "GND2")
		(16 "In7.Cu" signal "IN2")
		(18 "In8.Cu" signal "GND3")
		(20 "In9.Cu" signal "IN3")
		(22 "In10.Cu" signal "GND4")
		(24 "In11.Cu" signal "IN4")
		(26 "In12.Cu" signal "GND5")
		(28 "In13.Cu" signal "IN5")
		(30 "In14.Cu" signal "GND6")
		(32 "In15.Cu" signal "IN6")
		(34 "In16.Cu" signal "GND7")
		(2 "B.Cu" signal "BOTTOM")
		(9 "F.Adhes" user "F.Adhesive")
		(11 "B.Adhes" user "B.Adhesive")
		(13 "F.Paste" user "Package Geometry/Pastemask Top")
		(15 "B.Paste" user "Package Geometry/Pastemask Bottom")
		(5 "F.SilkS" user "Ref Des/Silkscreen Top")
		(7 "B.SilkS" user "Ref Des/Silkscreen Bottom")
		(1 "F.Mask" user "Board Geometry/Soldermask Top")
		(3 "B.Mask" user "Board Geometry/Soldermask Bottom")
		(17 "Dwgs.User" user "User.Drawings")
		(19 "Cmts.User" user "User.Comments")
		(21 "Eco1.User" user "User.Eco1")
		(23 "Eco2.User" user "User.Eco2")
		(25 "Edge.Cuts" user "Board Geometry/Outline")
		(27 "Margin" user)
		(31 "F.CrtYd" user "Package Geometry/Place Bound Top")
		(29 "B.CrtYd" user "Package Geometry/Place Bound Bottom")
		(35 "F.Fab" user "Ref Des/Assembly Top")
		(33 "B.Fab" user "Ref Des/Assembly Bottom")
	)
	(footprint ""
		(layer "B.Cu")
		(at 159.88665 -459.44663)
		(property "Reference" "X78"
			(at 0.1778 -1.92913 0)
			(unlocked yes)
			(layer "B.SilkS")
			(effects
				(font
					(size 0.7874 0.5842)
					(thickness 0.1524)
				)
				(justify left mirror)
			)
		)
		(property "Value" ""
			(at 0 0 0)
			(layer "B.Fab")
			(effects
				(font
					(size 1.27 1.27)
				)
				(justify mirror)
			)
		)
		(property "Device Type" "TP_TDR_4P_FTS_MPKT4_H025P0200_IO_TP15_TP_TDR_4P_DIP"
			(at -1.30175 1.27 270)
			(unlocked yes)
			(layer "B.Fab")
			(hide yes)
			(effects
				(font
					(size 0.635 0.4064)
					(thickness 0.1524)
				)
				(justify mirror)
			)
		)
		(property "User Part Number" "TP15"
			(at -1.30175 1.27 270)
			(unlocked yes)
			(layer "Cmts.User")
			(hide yes)
			(effects
				(font
					(size 0.635 0.4064)
					(thickness 0.1524)
				)
				(justify mirror)
			)
		)
		(duplicate_pad_numbers_are_jumpers no)
		(fp_line
			(start -2.54 -1.27)
			(end 0 -1.27)
			(stroke
				(width 0.1524)
				(type default)
			)
			(layer "B.SilkS")
		)
		(fp_line
			(start -2.54 -1.1303)
			(end -2.54 -1.27)
			(stroke
				(width 0.1524)
				(type default)
			)
			(layer "B.SilkS")
		)
		(fp_line
			(start -2.54 1.4097)
			(end -2.54 1.1303)
			(stroke
				(width 0.1524)
				(type default)
			)
			(layer "B.SilkS")
		)
		(fp_line
			(start -2.54 3.81)
			(end -2.54 3.6703)
			(stroke
				(width 0.1524)
				(type default)
			)
			(layer "B.SilkS")
		)
		(fp_line
			(start 0 -1.27)
			(end 0 -0.635)
			(stroke
				(width 0.1524)
				(type default)
			)
			(layer "B.SilkS")
		)
		(fp_line
			(start 0 0.635)
			(end 0 1.905)
			(stroke
				(width 0.1524)
				(type default)
			)
			(layer "B.SilkS")
		)
		(fp_line
			(start 0 3.175)
			(end 0 3.81)
			(stroke
				(width 0.1524)
				(type default)
			)
			(layer "B.SilkS")
		)
		(fp_line
			(start 0 3.81)
			(end -2.54 3.81)
			(stroke
				(width 0.1524)
				(type default)
			)
			(layer "B.SilkS")
		)
		(fp_poly
			(pts
				(xy 0.761746 0) (xy 2.285746 -0.762) (xy 2.285746 0.762)
			)
			(stroke
				(width 0)
				(type default)
			)
			(fill yes)
			(layer "B.SilkS")
		)
		(fp_line
			(start -2.54 -1.27)
			(end 0 -1.27)
			(stroke
				(width 0.1)
				(type default)
			)
			(layer "B.Fab")
		)
		(fp_line
			(start -2.54 3.81)
			(end -2.54 -1.27)
			(stroke
				(width 0.1)
				(type default)
			)
			(layer "B.Fab")
		)
		(fp_line
			(start 0 -1.27)
			(end 0 3.81)
			(stroke
				(width 0.1)
				(type default)
			)
			(layer "B.Fab")
		)
		(fp_line
			(start 0 3.81)
			(end -2.54 3.81)
			(stroke
				(width 0.1)
				(type default)
			)
			(layer "B.Fab")
		)
		(fp_poly
			(pts
				(xy 0.761746 0) (xy 2.285746 -0.762) (xy 2.285746 0.762)
			)
			(stroke
				(width 0)
				(type default)
			)
			(fill yes)
			(layer "B.Fab")
		)
		(pad "1" thru_hole circle
			(at 0 0 180)
			(size 1.0033 1.0033)
			(drill 0.249936)
			(layers "*.Cu" "*.Mask")
			(remove_unused_layers no)
			(net "TDR_DIFF_100_IN6_DIP")
			(clearance 0.10795)
			(padstack
				(mode front_inner_back)
				(layer "Inner"
					(shape circle)
					(size 0.8001 0.8001)
					(clearance 0.1524)
				)
				(layer "B.Cu"
					(shape circle)
					(size 1.0033 1.0033)
					(thermal_gap 0.10795)
					(clearance 0.10795)
				)
			)
		)
		(pad "2" thru_hole circle
			(at -2.54 0 180)
			(size 1.9939 1.9939)
			(drill 0.249936)
			(layers "*.Cu" "*.Mask")
			(remove_unused_layers no)
			(net "COUPON_GND1")
			(clearance 0.10795)
			(padstack
				(mode front_inner_back)
				(layer "Inner"
					(shape circle)
					(size 0.8001 0.8001)
					(clearance 0.1524)
				)
				(layer "B.Cu"
					(shape circle)
					(size 1.9939 1.9939)
					(thermal_gap 0.10795)
					(clearance 0.10795)
				)
			)
		)
		(pad "3" thru_hole circle
			(at -2.54 2.54 180)
			(size 1.9939 1.9939)
			(drill 0.249936)
			(layers "*.Cu" "*.Mask")
			(remove_unused_layers no)
			(net "COUPON_GND1")
			(clearance 0.10795)
			(padstack
				(mode front_inner_back)
				(layer "Inner"
					(shape circle)
					(size 0.8001 0.8001)
					(clearance 0.1524)
				)
				(layer "B.Cu"
					(shape circle)
					(size 1.9939 1.9939)
					(thermal_gap 0.10795)
					(clearance 0.10795)
				)
			)
		)
		(pad "4" thru_hole circle
			(at 0 2.54 180)
			(size 1.0033 1.0033)
			(drill 0.249936)
			(layers "*.Cu" "*.Mask")
			(remove_unused_layers no)
			(net "TDR_DIFF_100_IN6_DIN")
			(clearance 0.10795)
			(padstack
				(mode front_inner_back)
				(layer "Inner"
					(shape circle)
					(size 0.8001 0.8001)
					(clearance 0.1524)
				)
				(layer "B.Cu"
					(shape circle)
					(size 1.0033 1.0033)
					(thermal_gap 0.10795)
					(clearance 0.10795)
				)
			)
		)
	)
	(footprint ""
		(layer "B.Cu")
		(at 56.007 -136.652 -90)
		(property "Reference" "R36"
			(at 0 0 90)
			(layer "B.SilkS")
			(hide yes)
			(effects
				(font
					(size 1.27 1.27)
				)
				(justify mirror)
			)
		)
		(property "Value" ""
			(at 0 0 90)
			(layer "B.Fab")
			(effects
				(font
					(size 1.27 1.27)
				)
				(justify mirror)
			)
		)
		(duplicate_pad_numbers_are_jumpers no)
		(fp_line
			(start -0.7874 0.4064)
			(end 0.7874 0.4064)
			(stroke
				(width 0.1524)
				(type default)
			)
			(layer "B.SilkS")
		)
		(fp_line
			(start 0.7874 0.4064)
			(end 0.7874 -0.4064)
			(stroke
				(width 0.1524)
				(type default)
			)
			(layer "B.SilkS")
		)
		(fp_line
			(start -0.7874 -0.4064)
			(end -0.7874 0.4064)
			(stroke
				(width 0.1524)
				(type default)
			)
			(layer "B.SilkS")
		)
		(fp_line
			(start 0.7874 -0.4064)
			(end -0.7874 -0.4064)
			(stroke
				(width 0.1524)
				(type default)
			)
			(layer "B.SilkS")
		)
		(fp_line
			(start -0.67945 0.3048)
			(end -0.120396 0.3048)
			(stroke
				(width 0.1)
				(type default)
			)
			(layer "B.Fab")
		)
		(fp_line
			(start -0.120396 0.3048)
			(end -0.120396 0.2794)
			(stroke
				(width 0.1)
				(type default)
			)
			(layer "B.Fab")
		)
		(fp_line
			(start 0.12065 0.3048)
			(end 0.67945 0.3048)
			(stroke
				(width 0.1)
				(type default)
			)
			(layer "B.Fab")
		)
		(fp_line
			(start 0.67945 0.3048)
			(end 0.67945 -0.305054)
			(stroke
				(width 0.1)
				(type default)
			)
			(layer "B.Fab")
		)
		(fp_line
			(start -0.120396 0.2794)
			(end 0.12065 0.2794)
			(stroke
				(width 0.1)
				(type default)
			)
			(layer "B.Fab")
		)
		(fp_line
			(start 0.12065 0.2794)
			(end 0.12065 0.3048)
			(stroke
				(width 0.1)
				(type default)
			)
			(layer "B.Fab")
		)
		(fp_line
			(start -0.12065 -0.2794)
			(end -0.12065 -0.3048)
			(stroke
				(width 0.1)
				(type default)
			)
			(layer "B.Fab")
		)
		(fp_line
			(start 0.12065 -0.2794)
			(end -0.12065 -0.2794)
			(stroke
				(width 0.1)
				(type default)
			)
			(layer "B.Fab")
		)
		(fp_line
			(start -0.67945 -0.3048)
			(end -0.67945 0.3048)
			(stroke
				(width 0.1)
				(type default)
			)
			(layer "B.Fab")
		)
		(fp_line
			(start -0.12065 -0.3048)
			(end -0.67945 -0.3048)
			(stroke
				(width 0.1)
				(type default)
			)
			(layer "B.Fab")
		)
		(fp_line
			(start 0.12065 -0.305054)
			(end 0.12065 -0.2794)
			(stroke
				(width 0.1)
				(type default)
			)
			(layer "B.Fab")
		)
		(fp_line
			(start 0.67945 -0.305054)
			(end 0.12065 -0.305054)
			(stroke
				(width 0.1)
				(type default)
			)
			(layer "B.Fab")
		)
		(pad "1" smd circle
			(at 0.40005 0 90)
			(size 0 0)
			(layers "B.Cu" "B.Mask" "B.Paste")
			(net "RST_SMB_NIC_MUX_R_N")
		)
		(pad "2" smd circle
			(at -0.40005 0 90)
			(size 0 0)
			(layers "B.Cu" "B.Mask" "B.Paste")
			(net "RST_SMB_NIC0_MUX_N")
		)
	)
	(footprint ""
		(layer "B.Cu")
		(at 49.24552 -296.37482)
		(property "Reference" "C1124"
			(at 0 0 0)
			(layer "B.SilkS")
			(hide yes)
			(effects
				(font
					(size 1.27 1.27)
				)
				(justify mirror)
			)
		)
		(property "Value" ""
			(at 0 0 0)
			(layer "B.Fab")
			(effects
				(font
					(size 1.27 1.27)
				)
				(justify mirror)
			)
		)
		(duplicate_pad_numbers_are_jumpers no)
		(fp_line
			(start -0.299974 -0.150114)
			(end -0.299974 0.150114)
			(stroke
				(width 0.1)
				(type default)
			)
			(layer "B.Fab")
		)
		(fp_line
			(start -0.299974 0.150114)
			(end 0.299974 0.150114)
			(stroke
				(width 0.1)
				(type default)
			)
			(layer "B.Fab")
		)
		(fp_line
			(start 0.299974 -0.150114)
			(end -0.299974 -0.150114)
			(stroke
				(width 0.1)
				(type default)
			)
			(layer "B.Fab")
		)
		(fp_line
			(start 0.299974 0.150114)
			(end 0.299974 -0.150114)
			(stroke
				(width 0.1)
				(type default)
			)
			(layer "B.Fab")
		)
		(pad "1" smd rect
			(at 0.2667 0 180)
			(size 0.3048 0.381)
			(layers "B.Cu" "B.Mask" "B.Paste")
			(net "P0V8_PEX0")
		)
		(pad "2" smd rect
			(at -0.2667 0 180)
			(size 0.3048 0.381)
			(layers "B.Cu" "B.Mask" "B.Paste")
			(net "GND")
		)
	)
	(footprint ""
		(layer "B.Cu")
		(at 57.749948 -288.299906 90)
		(property "Reference" "C2943"
			(at 0 0 90)
			(layer "B.SilkS")
			(hide yes)
			(effects
				(font
					(size 1.27 1.27)
				)
				(justify mirror)
			)
		)
		(property "Value" ""
			(at 0 0 90)
			(layer "B.Fab")
			(effects
				(font
					(size 1.27 1.27)
				)
				(justify mirror)
			)
		)
		(duplicate_pad_numbers_are_jumpers no)
		(fp_line
			(start 0.299974 -0.150114)
			(end -0.299974 -0.150114)
			(stroke
				(width 0.1)
				(type default)
			)
			(layer "B.Fab")
		)
		(fp_line
			(start -0.299974 -0.150114)
			(end -0.299974 0.150114)
			(stroke
				(width 0.1)
				(type default)
			)
			(layer "B.Fab")
		)
		(fp_line
			(start 0.299974 0.150114)
			(end 0.299974 -0.150114)
			(stroke
				(width 0.1)
				(type default)
			)
			(layer "B.Fab")
		)
		(fp_line
			(start -0.299974 0.150114)
			(end 0.299974 0.150114)
			(stroke
				(width 0.1)
				(type default)
			)
			(layer "B.Fab")
		)
		(pad "1" smd rect
			(at 0.2667 0 270)
			(size 0.3048 0.381)
			(layers "B.Cu" "B.Mask" "B.Paste")
			(net "P1V25_PEX0")
		)
		(pad "2" smd rect
			(at -0.2667 0 270)
			(size 0.3048 0.381)
			(layers "B.Cu" "B.Mask" "B.Paste")
			(net "GND")
		)
	)
	(footprint ""
		(layer "B.Cu")
		(at 24.496522 -226.535996 -90)
		(property "Reference" "R3439"
			(at 0 0 90)
			(layer "B.SilkS")
			(hide yes)
			(effects
				(font
					(size 1.27 1.27)
				)
				(justify mirror)
			)
		)
		(property "Value" ""
			(at 0 0 90)
			(layer "B.Fab")
			(effects
				(font
					(size 1.27 1.27)
				)
				(justify mirror)
			)
		)
		(duplicate_pad_numbers_are_jumpers no)
		(fp_line
			(start -0.7874 0.4064)
			(end 0.7874 0.4064)
			(stroke
				(width 0.1524)
				(type default)
			)
			(layer "B.SilkS")
		)
		(fp_line
			(start 0.7874 0.4064)
			(end 0.7874 -0.4064)
			(stroke
				(width 0.1524)
				(type default)
			)
			(layer "B.SilkS")
		)
		(fp_line
			(start -0.7874 -0.4064)
			(end -0.7874 0.4064)
			(stroke
				(width 0.1524)
				(type default)
			)
			(layer "B.SilkS")
		)
		(fp_line
			(start 0.7874 -0.4064)
			(end -0.7874 -0.4064)
			(stroke
				(width 0.1524)
				(type default)
			)
			(layer "B.SilkS")
		)
		(fp_line
			(start -0.67945 0.3048)
			(end -0.120396 0.3048)
			(stroke
				(width 0.1)
				(type default)
			)
			(layer "B.Fab")
		)
		(fp_line
			(start -0.120396 0.3048)
			(end -0.120396 0.2794)
			(stroke
				(width 0.1)
				(type default)
			)
			(layer "B.Fab")
		)
		(fp_line
			(start 0.12065 0.3048)
			(end 0.67945 0.3048)
			(stroke
				(width 0.1)
				(type default)
			)
			(layer "B.Fab")
		)
		(fp_line
			(start 0.67945 0.3048)
			(end 0.67945 -0.305054)
			(stroke
				(width 0.1)
				(type default)
			)
			(layer "B.Fab")
		)
		(fp_line
			(start -0.120396 0.2794)
			(end 0.12065 0.2794)
			(stroke
				(width 0.1)
				(type default)
			)
			(layer "B.Fab")
		)
		(fp_line
			(start 0.12065 0.2794)
			(end 0.12065 0.3048)
			(stroke
				(width 0.1)
				(type default)
			)
			(layer "B.Fab")
		)
		(fp_line
			(start -0.12065 -0.2794)
			(end -0.12065 -0.3048)
			(stroke
				(width 0.1)
				(type default)
			)
			(layer "B.Fab")
		)
		(fp_line
			(start 0.12065 -0.2794)
			(end -0.12065 -0.2794)
			(stroke
				(width 0.1)
				(type default)
			)
			(layer "B.Fab")
		)
		(fp_line
			(start -0.67945 -0.3048)
			(end -0.67945 0.3048)
			(stroke
				(width 0.1)
				(type default)
			)
			(layer "B.Fab")
		)
		(fp_line
			(start -0.12065 -0.3048)
			(end -0.67945 -0.3048)
			(stroke
				(width 0.1)
				(type default)
			)
			(layer "B.Fab")
		)
		(fp_line
			(start 0.12065 -0.305054)
			(end 0.12065 -0.2794)
			(stroke
				(width 0.1)
				(type default)
			)
			(layer "B.Fab")
		)
		(fp_line
			(start 0.67945 -0.305054)
			(end 0.12065 -0.305054)
			(stroke
				(width 0.1)
				(type default)
			)
			(layer "B.Fab")
		)
		(pad "1" smd circle
			(at 0.40005 0 90)
			(size 0 0)
			(layers "B.Cu" "B.Mask" "B.Paste")
			(net "P1V8_PEX")
		)
		(pad "2" smd circle
			(at -0.40005 0 90)
			(size 0 0)
			(layers "B.Cu" "B.Mask" "B.Paste")
			(net "SPI_PEX0_CS_MUX_R_N")
		)
	)
	(footprint ""
		(layer "B.Cu")
		(at 65.824862 -297.79976 90)
		(property "Reference" "C1125"
			(at 0 0 90)
			(layer "B.SilkS")
			(hide yes)
			(effects
				(font
					(size 1.27 1.27)
				)
				(justify mirror)
			)
		)
		(property "Value" ""
			(at 0 0 90)
			(layer "B.Fab")
			(effects
				(font
					(size 1.27 1.27)
				)
				(justify mirror)
			)
		)
		(duplicate_pad_numbers_are_jumpers no)
		(fp_line
			(start 0.299974 -0.150114)
			(end -0.299974 -0.150114)
			(stroke
				(width 0.1)
				(type default)
			)
			(layer "B.Fab")
		)
		(fp_line
			(start -0.299974 -0.150114)
			(end -0.299974 0.150114)
			(stroke
				(width 0.1)
				(type default)
			)
			(layer "B.Fab")
		)
		(fp_line
			(start 0.299974 0.150114)
			(end 0.299974 -0.150114)
			(stroke
				(width 0.1)
				(type default)
			)
			(layer "B.Fab")
		)
		(fp_line
			(start -0.299974 0.150114)
			(end 0.299974 0.150114)
			(stroke
				(width 0.1)
				(type default)
			)
			(layer "B.Fab")
		)
		(pad "1" smd rect
			(at 0.2667 0 270)
			(size 0.3048 0.381)
			(layers "B.Cu" "B.Mask" "B.Paste")
			(net "P0V8_PEX0")
		)
		(pad "2" smd rect
			(at -0.2667 0 270)
			(size 0.3048 0.381)
			(layers "B.Cu" "B.Mask" "B.Paste")
			(net "GND")
		)
	)
	(footprint ""
		(layer "B.Cu")
		(at 343.694004 -217.187018 -90)
		(property "Reference" "C2056"
			(at 0 0 90)
			(layer "B.SilkS")
			(hide yes)
			(effects
				(font
					(size 1.27 1.27)
				)
				(justify mirror)
			)
		)
		(property "Value" ""
			(at 0 0 90)
			(layer "B.Fab")
			(effects
				(font
					(size 1.27 1.27)
				)
				(justify mirror)
			)
		)
		(duplicate_pad_numbers_are_jumpers no)
		(fp_line
			(start -0.69215 0.2921)
			(end 0.69215 0.2921)
			(stroke
				(width 0.1524)
				(type default)
			)
			(layer "B.SilkS")
		)
		(fp_line
			(start 0.69215 0.2921)
			(end 0.69215 -0.2921)
			(stroke
				(width 0.1524)
				(type default)
			)
			(layer "B.SilkS")
		)
		(fp_line
			(start -0.69215 -0.2921)
			(end -0.69215 0.2921)
			(stroke
				(width 0.1524)
				(type default)
			)
			(layer "B.SilkS")
		)
		(fp_line
			(start 0.69215 -0.2921)
			(end -0.69215 -0.2921)
			(stroke
				(width 0.1524)
				(type default)
			)
			(layer "B.SilkS")
		)
		(fp_line
			(start -0.51435 0.2794)
			(end 0.51435 0.2794)
			(stroke
				(width 0.1)
				(type default)
			)
			(layer "B.Fab")
		)
		(fp_line
			(start 0.51435 0.2794)
			(end 0.51435 -0.2794)
			(stroke
				(width 0.1)
				(type default)
			)
			(layer "B.Fab")
		)
		(fp_line
			(start -0.51435 -0.2794)
			(end -0.51435 0.2794)
			(stroke
				(width 0.1)
				(type default)
			)
			(layer "B.Fab")
		)
		(fp_line
			(start 0.51435 -0.2794)
			(end -0.51435 -0.2794)
			(stroke
				(width 0.1)
				(type default)
			)
			(layer "B.Fab")
		)
		(pad "1" smd circle
			(at 0.40005 0 90)
			(size 0 0)
			(layers "B.Cu" "B.Mask" "B.Paste")
			(net "P3V3_FPGA_VCCIO2")
		)
		(pad "2" smd circle
			(at -0.40005 0 90)
			(size 0 0)
			(layers "B.Cu" "B.Mask" "B.Paste")
			(net "GND")
		)
		(zone
			(layer "B.Cu")
			(hatch none 0.5)
			(connect_pads
				(clearance 0)
			)
			(min_thickness 0.25)
			(keepout
				(tracks not_allowed)
				(vias allowed)
				(pads allowed)
				(copperpour not_allowed)
				(footprints allowed)
			)
			(placement
				(enabled no)
				(sheetname "")
			)
			(fill
				(thermal_gap 0.5)
				(thermal_bridge_width 0.5)
				(island_removal_mode 0)
			)
			(polygon
				(pts
					(xy 343.606374 -216.996518) (xy 343.548208 -217.087958) (xy 343.548208 -217.287348) (xy 343.606374 -217.377518)
					(xy 343.781634 -217.377518) (xy 343.840054 -217.287348) (xy 343.840054 -217.087958) (xy 343.781888 -216.996518)
				)
			)
		)
	)
)
